(kicad_pcb
	(version 20260206)
	(generator "pcbnew")
	(generator_version "10.0")
	(general
		(thickness 1.6)
		(legacy_teardrops no)
	)
	(paper "A4")
	(title_block
		(title "03242023_DA0F0TMBIJ0_F0T_Motherboard_J_brd_V01_OCP.brd")
		(comment 1 "Grand Teton / footprints 1680-1681 of 6105")
	)
	(layers
		(0 "F.Cu" signal "TOP")
		(4 "In1.Cu" signal "GND")
		(6 "In2.Cu" signal "IN1")
		(8 "In3.Cu" signal "GND1")
		(10 "In4.Cu" signal "IN2")
		(12 "In5.Cu" signal "GND2")
		(14 "In6.Cu" signal "IN3")
		(16 "In7.Cu" signal "GND3")
		(18 "In8.Cu" signal "VCC")
		(20 "In9.Cu" signal "VCC1")
		(22 "In10.Cu" signal "GND4")
		(24 "In11.Cu" signal "IN4")
		(26 "In12.Cu" signal "GND5")
		(28 "In13.Cu" signal "IN5")
		(30 "In14.Cu" signal "GND6")
		(32 "In15.Cu" signal "IN6")
		(34 "In16.Cu" signal "GND7")
		(2 "B.Cu" signal "BOTTOM")
		(9 "F.Adhes" user "F.Adhesive")
		(11 "B.Adhes" user "B.Adhesive")
		(13 "F.Paste" user "Package Geometry/Pastemask Top")
		(15 "B.Paste" user "Package Geometry/Pastemask Bottom")
		(5 "F.SilkS" user "Ref Des/Silkscreen Top")
		(7 "B.SilkS" user "Ref Des/Silkscreen Bottom")
		(1 "F.Mask" user "Board Geometry/Soldermask Top")
		(3 "B.Mask" user "Board Geometry/Soldermask Bottom")
		(17 "Dwgs.User" user "User.Drawings")
		(19 "Cmts.User" user "User.Comments")
		(21 "Eco1.User" user "User.Eco1")
		(23 "Eco2.User" user "User.Eco2")
		(25 "Edge.Cuts" user "Board Geometry/Outline")
		(27 "Margin" user)
		(31 "F.CrtYd" user "Package Geometry/Place Bound Top")
		(29 "B.CrtYd" user "Package Geometry/Place Bound Bottom")
		(35 "F.Fab" user "Ref Des/Assembly Top")
		(33 "B.Fab" user "Ref Des/Assembly Bottom")
	)
	(footprint ""
		(layer "F.Cu")
		(at 349.523304 -333.525368 -90)
		(property "Reference" "PC294_P0_2"
			(at 0 0 270)
			(layer "F.SilkS")
			(hide yes)
			(effects
				(font
					(size 1.27 1.27)
				)
			)
		)
		(property "Value" ""
			(at 0 0 270)
			(layer "F.Fab")
			(effects
				(font
					(size 1.27 1.27)
				)
			)
		)
		(duplicate_pad_numbers_are_jumpers no)
		(fp_line
			(start -0.7874 0.4064)
			(end -0.7874 -0.4064)
			(stroke
				(width 0.1524)
				(type default)
			)
			(layer "F.SilkS")
		)
		(fp_line
			(start 0.7874 0.4064)
			(end -0.7874 0.4064)
			(stroke
				(width 0.1524)
				(type default)
			)
			(layer "F.SilkS")
		)
		(fp_line
			(start -0.7874 -0.4064)
			(end 0.7874 -0.4064)
			(stroke
				(width 0.1524)
				(type default)
			)
			(layer "F.SilkS")
		)
		(fp_line
			(start 0.7874 -0.4064)
			(end 0.7874 0.4064)
			(stroke
				(width 0.1524)
				(type default)
			)
			(layer "F.SilkS")
		)
		(fp_line
			(start -0.67945 0.3048)
			(end -0.67945 -0.305054)
			(stroke
				(width 0.1)
				(type default)
			)
			(layer "F.Fab")
		)
		(fp_line
			(start -0.12065 0.3048)
			(end -0.67945 0.3048)
			(stroke
				(width 0.1)
				(type default)
			)
			(layer "F.Fab")
		)
		(fp_line
			(start 0.120396 0.3048)
			(end 0.120396 0.2794)
			(stroke
				(width 0.1)
				(type default)
			)
			(layer "F.Fab")
		)
		(fp_line
			(start 0.67945 0.3048)
			(end 0.120396 0.3048)
			(stroke
				(width 0.1)
				(type default)
			)
			(layer "F.Fab")
		)
		(fp_line
			(start -0.12065 0.2794)
			(end -0.12065 0.3048)
			(stroke
				(width 0.1)
				(type default)
			)
			(layer "F.Fab")
		)
		(fp_line
			(start 0.120396 0.2794)
			(end -0.12065 0.2794)
			(stroke
				(width 0.1)
				(type default)
			)
			(layer "F.Fab")
		)
		(fp_line
			(start -0.12065 -0.2794)
			(end 0.12065 -0.2794)
			(stroke
				(width 0.1)
				(type default)
			)
			(layer "F.Fab")
		)
		(fp_line
			(start 0.12065 -0.2794)
			(end 0.12065 -0.3048)
			(stroke
				(width 0.1)
				(type default)
			)
			(layer "F.Fab")
		)
		(fp_line
			(start 0.12065 -0.3048)
			(end 0.67945 -0.3048)
			(stroke
				(width 0.1)
				(type default)
			)
			(layer "F.Fab")
		)
		(fp_line
			(start 0.67945 -0.3048)
			(end 0.67945 0.3048)
			(stroke
				(width 0.1)
				(type default)
			)
			(layer "F.Fab")
		)
		(fp_line
			(start -0.67945 -0.305054)
			(end -0.12065 -0.305054)
			(stroke
				(width 0.1)
				(type default)
			)
			(layer "F.Fab")
		)
		(fp_line
			(start -0.12065 -0.305054)
			(end -0.12065 -0.2794)
			(stroke
				(width 0.1)
				(type default)
			)
			(layer "F.Fab")
		)
		(pad "1" smd circle
			(at -0.40005 0 270)
			(size 0 0)
			(layers "F.Cu" "F.Mask" "F.Paste")
			(net "PVCCIN_CPU0_PVCC")
		)
		(pad "2" smd circle
			(at 0.40005 0 270)
			(size 0 0)
			(layers "F.Cu" "F.Mask" "F.Paste")
			(net "GND")
		)
	)
	(footprint ""
		(layer "F.Cu")
		(at 430.643284 -179.201572 -90)
		(property "Reference" "PR1303"
			(at 0 0 270)
			(layer "F.SilkS")
			(hide yes)
			(effects
				(font
					(size 1.27 1.27)
				)
			)
		)
		(property "Value" ""
			(at 0 0 270)
			(layer "F.Fab")
			(effects
				(font
					(size 1.27 1.27)
				)
			)
		)
		(duplicate_pad_numbers_are_jumpers no)
		(fp_line
			(start -0.7874 0.4064)
			(end -0.7874 -0.4064)
			(stroke
				(width 0.1524)
				(type default)
			)
			(layer "F.SilkS")
		)
		(fp_line
			(start 0.7874 0.4064)
			(end -0.7874 0.4064)
			(stroke
				(width 0.1524)
				(type default)
			)
			(layer "F.SilkS")
		)
		(fp_line
			(start -0.7874 -0.4064)
			(end 0.7874 -0.4064)
			(stroke
				(width 0.1524)
				(type default)
			)
			(layer "F.SilkS")
		)
		(fp_line
			(start 0.7874 -0.4064)
			(end 0.7874 0.4064)
			(stroke
				(width 0.1524)
				(type default)
			)
			(layer "F.SilkS")
		)
		(fp_line
			(start -0.67945 0.3048)
			(end -0.67945 -0.305054)
			(stroke
				(width 0.1)
				(type default)
			)
			(layer "F.Fab")
		)
		(fp_line
			(start -0.12065 0.3048)
			(end -0.67945 0.3048)
			(stroke
				(width 0.1)
				(type default)
			)
			(layer "F.Fab")
		)
		(fp_line
			(start 0.120396 0.3048)
			(end 0.120396 0.2794)
			(stroke
				(width 0.1)
				(type default)
			)
			(layer "F.Fab")
		)
		(fp_line
			(start 0.67945 0.3048)
			(end 0.120396 0.3048)
			(stroke
				(width 0.1)
				(type default)
			)
			(layer "F.Fab")
		)
		(fp_line
			(start -0.12065 0.2794)
			(end -0.12065 0.3048)
			(stroke
				(width 0.1)
				(type default)
			)
			(layer "F.Fab")
		)
		(fp_line
			(start 0.120396 0.2794)
			(end -0.12065 0.2794)
			(stroke
				(width 0.1)
				(type default)
			)
			(layer "F.Fab")
		)
		(fp_line
			(start -0.12065 -0.2794)
			(end 0.12065 -0.2794)
			(stroke
				(width 0.1)
				(type default)
			)
			(layer "F.Fab")
		)
		(fp_line
			(start 0.12065 -0.2794)
			(end 0.12065 -0.3048)
			(stroke
				(width 0.1)
				(type default)
			)
			(layer "F.Fab")
		)
		(fp_line
			(start 0.12065 -0.3048)
			(end 0.67945 -0.3048)
			(stroke
				(width 0.1)
				(type default)
			)
			(layer "F.Fab")
		)
		(fp_line
			(start 0.67945 -0.3048)
			(end 0.67945 0.3048)
			(stroke
				(width 0.1)
				(type default)
			)
			(layer "F.Fab")
		)
		(fp_line
			(start -0.67945 -0.305054)
			(end -0.12065 -0.305054)
			(stroke
				(width 0.1)
				(type default)
			)
			(layer "F.Fab")
		)
		(fp_line
			(start -0.12065 -0.305054)
			(end -0.12065 -0.2794)
			(stroke
				(width 0.1)
				(type default)
			)
			(layer "F.Fab")
		)
		(pad "1" smd circle
			(at -0.40005 0 270)
			(size 0 0)
			(layers "F.Cu" "F.Mask" "F.Paste")
			(net "PVNN_MAIN_CPU0_CS")
		)
		(pad "2" smd circle
			(at 0.40005 0 270)
			(size 0 0)
			(layers "F.Cu" "F.Mask" "F.Paste")
			(net "GND")
		)
	)
)
